# BASEBOARD_FAB2 (Tioga Pass) — schematic netlist excerpt (pin names and nets, part order shuffled) for the footprints in the layout excerpt that follows; sources: Cadence DE-HDL packaged netlist, KiCad conversion of Wiwynn_Tioga_Pass_MB.brd

C2G10  CAP_A  47UF 4V 20% X5R  pkg 0603V  page 225 : A = PVDDQ_GHJ ; B = GND
C7B13  CAP  2200PF 50V 10% X7R  pkg 0402LF  page 232 : A = VR_COMP_PVPP_DEF ; B = VR_FB_PVPP_DEF
C9F3  CAP  10UF 6.3V 20% X6S  pkg 0603  page 238 : A = P3V3_STBY ; B = GND

(kicad_pcb
	(version 20260206)
	(generator "pcbnew")
	(generator_version "10.0")
	(general
		(thickness 1.6)
		(legacy_teardrops no)
	)
	(paper "A4")
	(title_block
		(title "Wiwynn_Tioga_Pass_MB.brd")
		(comment 1 "Tioga Pass / footprints 1753-1755 of 4770")
	)
	(layers
		(0 "F.Cu" signal "TOP")
		(4 "In1.Cu" signal "L2GND")
		(6 "In2.Cu" signal "L3")
		(8 "In3.Cu" signal "L4GND")
		(10 "In4.Cu" signal "L5")
		(12 "In5.Cu" signal "L6GND")
		(14 "In6.Cu" signal "L7VCC")
		(16 "In7.Cu" signal "L8VCC")
		(18 "In8.Cu" signal "L9GND")
		(20 "In9.Cu" signal "L10")
		(22 "In10.Cu" signal "L11GND")
		(24 "In11.Cu" signal "L12")
		(26 "In12.Cu" signal "L13GND")
		(2 "B.Cu" signal "BOTTOM")
		(9 "F.Adhes" user "F.Adhesive")
		(11 "B.Adhes" user "B.Adhesive")
		(13 "F.Paste" user "Package Geometry/Pastemask Top")
		(15 "B.Paste" user "Package Geometry/Pastemask Bottom")
		(5 "F.SilkS" user "Ref Des/Silkscreen Top")
		(7 "B.SilkS" user "Ref Des/Silkscreen Bottom")
		(1 "F.Mask" user "Board Geometry/Soldermask Top")
		(3 "B.Mask" user "Board Geometry/Soldermask Bottom")
		(17 "Dwgs.User" user "User.Drawings")
		(19 "Cmts.User" user "User.Comments")
		(21 "Eco1.User" user "User.Eco1")
		(23 "Eco2.User" user "User.Eco2")
		(25 "Edge.Cuts" user "Board Geometry/Outline")
		(27 "Margin" user)
		(31 "F.CrtYd" user "Package Geometry/Place Bound Top")
		(29 "B.CrtYd" user "Package Geometry/Place Bound Bottom")
		(35 "F.Fab" user "Ref Des/Assembly Top")
		(33 "B.Fab" user "Ref Des/Assembly Bottom")
	)
	(footprint ""
		(layer "F.Cu")
		(at 83.856068 -3.3528 -90)
		(property "Reference" "C2G10"
			(at 1.848866 0.752348 270)
			(unlocked yes)
			(layer "F.SilkS")
			(effects
				(font
					(size 1.27 0.9652)
					(thickness 0.1524)
				)
			)
		)
		(property "Value" ""
			(at 0 0 270)
			(layer "F.Fab")
			(effects
				(font
					(size 1.27 1.27)
				)
			)
		)
		(duplicate_pad_numbers_are_jumpers no)
		(fp_rect
			(start -0.500126 1.598422)
			(end 0.500126 -0.201422)
			(stroke
				(width 0)
				(type default)
			)
			(fill no)
			(layer "F.CrtYd")
		)
		(fp_line
			(start -0.500126 1.598422)
			(end -0.500126 -0.201422)
			(stroke
				(width 0.1)
				(type default)
			)
			(layer "F.Fab")
		)
		(fp_line
			(start 0.500126 1.598422)
			(end -0.500126 1.598422)
			(stroke
				(width 0.1)
				(type default)
			)
			(layer "F.Fab")
		)
		(fp_line
			(start -0.500126 -0.201422)
			(end 0.500126 -0.201422)
			(stroke
				(width 0.1)
				(type default)
			)
			(layer "F.Fab")
		)
		(fp_line
			(start 0.500126 -0.201422)
			(end 0.500126 1.598422)
			(stroke
				(width 0.1)
				(type default)
			)
			(layer "F.Fab")
		)
		(pad "1" smd rect
			(at 0 0 180)
			(size 0.889 0.9906)
			(layers "F.Cu" "F.Mask" "F.Paste")
			(net "PVDDQ_GHJ")
		)
		(pad "2" smd rect
			(at 0 1.397 180)
			(size 0.889 0.9906)
			(layers "F.Cu" "F.Mask" "F.Paste")
			(net "GND")
		)
		(zone
			(layer "F.Cu")
			(hatch none 0.5)
			(connect_pads
				(clearance 0)
			)
			(min_thickness 0.25)
			(keepout
				(tracks not_allowed)
				(vias allowed)
				(pads allowed)
				(copperpour not_allowed)
				(footprints allowed)
			)
			(placement
				(enabled no)
				(sheetname "")
			)
			(fill
				(thermal_gap 0.5)
				(thermal_bridge_width 0.5)
				(island_removal_mode 0)
			)
			(polygon
				(pts
					(xy 82.903568 -3.8481) (xy 82.903568 -2.8575) (xy 83.411568 -2.8575) (xy 83.411568 -3.8481)
				)
			)
		)
		(zone
			(layer "F.Cu")
			(hatch none 0.5)
			(connect_pads
				(clearance 0)
			)
			(min_thickness 0.25)
			(keepout
				(tracks allowed)
				(vias not_allowed)
				(pads allowed)
				(copperpour not_allowed)
				(footprints allowed)
			)
			(placement
				(enabled no)
				(sheetname "")
			)
			(fill
				(thermal_gap 0.5)
				(thermal_bridge_width 0.5)
				(island_removal_mode 0)
			)
			(polygon
				(pts
					(xy 82.903568 -3.8481) (xy 82.903568 -2.8575) (xy 83.411568 -2.8575) (xy 83.411568 -3.8481)
				)
			)
		)
	)
	(footprint ""
		(layer "F.Cu")
		(at 465.328 -41.275)
		(property "Reference" "C9F3"
			(at 0 0 0)
			(layer "F.SilkS")
			(hide yes)
			(effects
				(font
					(size 1.27 1.27)
				)
			)
		)
		(property "Value" ""
			(at 0 0 0)
			(layer "F.Fab")
			(effects
				(font
					(size 1.27 1.27)
				)
			)
		)
		(duplicate_pad_numbers_are_jumpers no)
		(fp_poly
			(pts
				(xy -0.4953 -0.2032) (xy 0.4953 -0.2032) (xy 0.4953 1.6002) (xy -0.4953 1.6002)
			)
			(stroke
				(width 0)
				(type default)
			)
			(fill no)
			(layer "F.CrtYd")
		)
		(fp_line
			(start -0.4953 -0.2032)
			(end 0.4953 -0.2032)
			(stroke
				(width 0.1)
				(type default)
			)
			(layer "F.Fab")
		)
		(fp_line
			(start -0.4953 1.6002)
			(end -0.4953 -0.2032)
			(stroke
				(width 0.1)
				(type default)
			)
			(layer "F.Fab")
		)
		(fp_line
			(start 0.4953 -0.2032)
			(end 0.4953 1.6002)
			(stroke
				(width 0.1)
				(type default)
			)
			(layer "F.Fab")
		)
		(fp_line
			(start 0.4953 1.6002)
			(end -0.4953 1.6002)
			(stroke
				(width 0.1)
				(type default)
			)
			(layer "F.Fab")
		)
		(pad "1" smd rect
			(at 0 0)
			(size 0.762 0.889)
			(layers "F.Cu" "F.Mask" "F.Paste")
			(net "P3V3_STBY")
		)
		(pad "2" smd rect
			(at 0 1.397)
			(size 0.762 0.889)
			(layers "F.Cu" "F.Mask" "F.Paste")
			(net "GND")
		)
		(zone
			(layer "F.Cu")
			(hatch none 0.5)
			(connect_pads
				(clearance 0)
			)
			(min_thickness 0.25)
			(keepout
				(tracks not_allowed)
				(vias allowed)
				(pads allowed)
				(copperpour not_allowed)
				(footprints allowed)
			)
			(placement
				(enabled no)
				(sheetname "")
			)
			(fill
				(thermal_gap 0.5)
				(thermal_bridge_width 0.5)
				(island_removal_mode 0)
			)
			(polygon
				(pts
					(xy 464.947 -40.8305) (xy 465.709 -40.8305) (xy 465.709 -40.3225) (xy 464.947 -40.3225)
				)
			)
		)
	)
	(footprint ""
		(layer "F.Cu")
		(at 337.82 -128.2065 180)
		(property "Reference" "C7B13"
			(at 0 0 180)
			(layer "F.SilkS")
			(hide yes)
			(effects
				(font
					(size 1.27 1.27)
				)
			)
		)
		(property "Value" ""
			(at 0 0 180)
			(layer "F.Fab")
			(effects
				(font
					(size 1.27 1.27)
				)
			)
		)
		(duplicate_pad_numbers_are_jumpers no)
		(fp_poly
			(pts
				(xy 0.3048 -0.1016) (xy 0.3048 0.9906) (xy -0.3048 0.9906) (xy -0.3048 -0.1016)
			)
			(stroke
				(width 0)
				(type default)
			)
			(fill no)
			(layer "F.CrtYd")
		)
		(fp_line
			(start 0.3048 0.9906)
			(end 0.3048 -0.1016)
			(stroke
				(width 0.1)
				(type default)
			)
			(layer "F.Fab")
		)
		(fp_line
			(start 0.3048 -0.1016)
			(end -0.3048 -0.1016)
			(stroke
				(width 0.1)
				(type default)
			)
			(layer "F.Fab")
		)
		(fp_line
			(start -0.3048 0.9906)
			(end 0.3048 0.9906)
			(stroke
				(width 0.1)
				(type default)
			)
			(layer "F.Fab")
		)
		(fp_line
			(start -0.3048 -0.1016)
			(end -0.3048 0.9906)
			(stroke
				(width 0.1)
				(type default)
			)
			(layer "F.Fab")
		)
		(pad "1" smd rect
			(at 0 0 180)
			(size 0.508 0.508)
			(layers "F.Cu" "F.Mask" "F.Paste")
			(net "VR_COMP_PVPP_DEF")
		)
		(pad "2" smd rect
			(at 0 0.889 180)
			(size 0.508 0.508)
			(layers "F.Cu" "F.Mask" "F.Paste")
			(net "VR_FB_PVPP_DEF")
		)
		(zone
			(layer "F.Cu")
			(hatch none 0.5)
			(connect_pads
				(clearance 0)
			)
			(min_thickness 0.25)
			(keepout
				(tracks not_allowed)
				(vias allowed)
				(pads allowed)
				(copperpour not_allowed)
				(footprints allowed)
			)
			(placement
				(enabled no)
				(sheetname "")
			)
			(fill
				(thermal_gap 0.5)
				(thermal_bridge_width 0.5)
				(island_removal_mode 0)
			)
			(polygon
				(pts
					(xy 338.074 -128.8415) (xy 337.566 -128.8415) (xy 337.566 -128.4605) (xy 338.074 -128.4605)
				)
			)
		)
		(zone
			(layer "F.Cu")
			(hatch none 0.5)
			(connect_pads
				(clearance 0)
			)
			(min_thickness 0.25)
			(keepout
				(tracks allowed)
				(vias not_allowed)
				(pads allowed)
				(copperpour not_allowed)
				(footprints allowed)
			)
			(placement
				(enabled no)
				(sheetname "")
			)
			(fill
				(thermal_gap 0.5)
				(thermal_bridge_width 0.5)
				(island_removal_mode 0)
			)
			(polygon
				(pts
					(xy 338.074 -128.4605) (xy 337.566 -128.4605) (xy 337.566 -128.8415) (xy 338.074 -128.8415)
				)
			)
		)
	)
)
